(kicad_pcb
	(version 20241229)
	(generator "pcbnew")
	(generator_version "9.0")
	(general
		(thickness 1.61)
		(legacy_teardrops no)
	)
	(paper "A3")
	(title_block
		(title "RDIMM DDR5 Tester")
		(date "2026-05-21")
		(rev "2.2.0")
		(company "Antmicro")
		(comment 9 "footprints 149-153 of 796")
	)
	(layers
		(0 "F.Cu" signal)
		(4 "In1.Cu" power)
		(6 "In2.Cu" mixed)
		(8 "In3.Cu" power)
		(10 "In4.Cu" mixed)
		(12 "In5.Cu" power)
		(14 "In6.Cu" mixed)
		(16 "In7.Cu" power)
		(18 "In8.Cu" power)
		(20 "In9.Cu" mixed)
		(22 "In10.Cu" power)
		(2 "B.Cu" signal)
		(9 "F.Adhes" user "F.Adhesive")
		(11 "B.Adhes" user "B.Adhesive")
		(13 "F.Paste" user)
		(15 "B.Paste" user)
		(5 "F.SilkS" user "F.Silkscreen")
		(7 "B.SilkS" user "B.Silkscreen")
		(1 "F.Mask" user)
		(3 "B.Mask" user)
		(17 "Dwgs.User" user "User.Drawings")
		(19 "Cmts.User" user "User.Comments")
		(21 "Eco1.User" user "User.Eco1")
		(23 "Eco2.User" user "User.Eco2")
		(25 "Edge.Cuts" user)
		(27 "Margin" user)
		(31 "F.CrtYd" user "F.Courtyard")
		(29 "B.CrtYd" user "B.Courtyard")
		(35 "F.Fab" user)
		(33 "B.Fab" user)
	)
	(footprint "antmicro-footprints:L_WE-HCM-7050"
		(layer "F.Cu")
		(at 229.15 174.725 90)
		(property "Reference" "L2"
			(at -2.9 -3.9 90)
			(layer "F.SilkS")
			(effects
				(font
					(size 0.7 0.7)
					(thickness 0.15)
				)
				(justify left bottom)
			)
		)
		(property "Value" "L_150n_30A_WE-HCM-7050"
			(at -2.9 5.2 90)
			(layer "F.Fab")
			(effects
				(font
					(size 0.7 0.7)
					(thickness 0.15)
				)
				(justify left bottom)
			)
		)
		(property "Datasheet" "https://www.we-online.com/components/products/datasheet/744302015.pdf"
			(at 0 0 90)
			(layer "F.Fab")
			(hide yes)
			(effects
				(font
					(size 1.27 1.27)
					(thickness 0.15)
				)
			)
		)
		(property "Val" "150n/30A"
			(at 0 0 90)
			(unlocked yes)
			(layer "F.Fab")
			(hide yes)
			(effects
				(font
					(size 1 1)
					(thickness 0.15)
				)
			)
		)
		(property "Manufacturer" "Würth Elektronik"
			(at 0 0 90)
			(unlocked yes)
			(layer "F.Fab")
			(hide yes)
			(effects
				(font
					(size 1 1)
					(thickness 0.15)
				)
			)
		)
		(property "MPN" "744302015"
			(at 0 0 90)
			(unlocked yes)
			(layer "F.Fab")
			(hide yes)
			(effects
				(font
					(size 1 1)
					(thickness 0.15)
				)
			)
		)
		(property "ISat" "35 A"
			(at 0 0 90)
			(unlocked yes)
			(layer "F.Fab")
			(hide yes)
			(effects
				(font
					(size 1 1)
					(thickness 0.15)
				)
			)
		)
		(property "IMax" "30 A"
			(at 0 0 90)
			(unlocked yes)
			(layer "F.Fab")
			(hide yes)
			(effects
				(font
					(size 1 1)
					(thickness 0.15)
				)
			)
		)
		(property "Size" "7.15x7"
			(at 0 0 90)
			(unlocked yes)
			(layer "F.Fab")
			(hide yes)
			(effects
				(font
					(size 1 1)
					(thickness 0.15)
				)
			)
		)
		(property "Author" "Antmicro"
			(at 0 0 90)
			(unlocked yes)
			(layer "F.Fab")
			(hide yes)
			(effects
				(font
					(size 1 1)
					(thickness 0.15)
				)
			)
		)
		(property "License" "Apache-2.0"
			(at 0 0 90)
			(unlocked yes)
			(layer "F.Fab")
			(hide yes)
			(effects
				(font
					(size 1 1)
					(thickness 0.15)
				)
			)
		)
		(sheetname "/Supply/DC-DC VCCINT/")
		(sheetfile "dc-dc-vccint.kicad_sch")
		(attr smd)
		(fp_line
			(start 3.6 -3.6)
			(end -3.6 -3.6)
			(stroke
				(width 0.15)
				(type solid)
			)
			(layer "F.SilkS")
		)
		(fp_line
			(start -3.6 -3.6)
			(end -3.6 -1.8)
			(stroke
				(width 0.15)
				(type solid)
			)
			(layer "F.SilkS")
		)
		(fp_line
			(start 3.6 -1.8)
			(end 3.6 -3.6)
			(stroke
				(width 0.15)
				(type solid)
			)
			(layer "F.SilkS")
		)
		(fp_line
			(start 3.6 1.8)
			(end 3.6 3.6)
			(stroke
				(width 0.15)
				(type solid)
			)
			(layer "F.SilkS")
		)
		(fp_line
			(start -3.6 1.8)
			(end -3.6 3.6)
			(stroke
				(width 0.15)
				(type solid)
			)
			(layer "F.SilkS")
		)
		(fp_line
			(start 3.6 3.6)
			(end -3.6 3.6)
			(stroke
				(width 0.15)
				(type solid)
			)
			(layer "F.SilkS")
		)
		(fp_rect
			(start -3.9 -3.75)
			(end 3.9 3.75)
			(stroke
				(width 0.05)
				(type solid)
			)
			(fill no)
			(layer "F.CrtYd")
		)
		(fp_rect
			(start -3.5 -3.5)
			(end 3.5 3.5)
			(stroke
				(width 0.15)
				(type solid)
			)
			(fill no)
			(layer "F.Fab")
		)
		(fp_text user "License: Apache-2.0"
			(at -4.25 8.4 90)
			(layer "F.Fab")
			(effects
				(font
					(size 0.7 0.7)
					(thickness 0.15)
				)
				(justify left bottom)
			)
		)
		(fp_text user "${REFERENCE}"
			(at -4.25 7.2 90)
			(layer "F.Fab")
			(effects
				(font
					(size 0.7 0.7)
					(thickness 0.15)
				)
				(justify left bottom)
			)
		)
		(fp_text user "Author: Antmicro"
			(at -4.25 9.6 90)
			(layer "F.Fab")
			(effects
				(font
					(size 0.7 0.7)
					(thickness 0.15)
				)
				(justify left bottom)
			)
		)
		(pad "1" smd roundrect
			(at -2.65 0 90)
			(size 2 3.05)
			(layers "F.Cu" "F.Mask" "F.Paste")
			(roundrect_rratio 0.1)
			(net 207 "Net-(C216-Pad2)")
			(pintype "passive")
		)
		(pad "2" smd roundrect
			(at 2.65 0 270)
			(size 2 3.05)
			(layers "F.Cu" "F.Mask" "F.Paste")
			(roundrect_rratio 0.1)
			(net 224 "/Supply/DC-DC VCCINT/0V85_REG1")
			(pintype "passive")
		)
	)
	(footprint "antmicro-footprints:C_0603_1608Metric"
		(layer "F.Cu")
		(at 248.87 173.972001 -90)
		(descr "Capacitor SMD 0603")
		(tags "capacitor 0603")
		(property "Reference" "C187"
			(at 1.277999 -0.63 90)
			(layer "F.SilkS")
			(effects
				(font
					(size 0.7 0.7)
					(thickness 0.15)
				)
				(justify right bottom)
			)
		)
		(property "Value" "C_22u_0603"
			(at -1.42757 1.770288 90)
			(layer "F.Fab")
			(effects
				(font
					(size 0.7 0.7)
					(thickness 0.15)
				)
				(justify right bottom)
			)
		)
		(property "Datasheet" "https://www.murata.com/products/productdetail?partno=GRM188R60J226MEA0%23"
			(at 0 0 270)
			(layer "F.Fab")
			(hide yes)
			(effects
				(font
					(size 1.27 1.27)
					(thickness 0.15)
				)
			)
		)
		(property "Manufacturer" "Murata"
			(at 0 0 270)
			(unlocked yes)
			(layer "F.Fab")
			(hide yes)
			(effects
				(font
					(size 1 1)
					(thickness 0.15)
				)
			)
		)
		(property "MPN" "GRM188R60J226MEA0D"
			(at 0 0 270)
			(unlocked yes)
			(layer "F.Fab")
			(hide yes)
			(effects
				(font
					(size 1 1)
					(thickness 0.15)
				)
			)
		)
		(property "Val" "22u"
			(at 0 0 270)
			(unlocked yes)
			(layer "F.Fab")
			(hide yes)
			(effects
				(font
					(size 1 1)
					(thickness 0.15)
				)
			)
		)
		(property "License" "Apache-2.0"
			(at 0 0 270)
			(unlocked yes)
			(layer "F.Fab")
			(hide yes)
			(effects
				(font
					(size 1 1)
					(thickness 0.15)
				)
			)
		)
		(property "Author" "Antmicro"
			(at 0 0 270)
			(unlocked yes)
			(layer "F.Fab")
			(hide yes)
			(effects
				(font
					(size 1 1)
					(thickness 0.15)
				)
			)
		)
		(property "Voltage" ""
			(at 0 0 270)
			(unlocked yes)
			(layer "F.Fab")
			(hide yes)
			(effects
				(font
					(size 1 1)
					(thickness 0.15)
				)
			)
		)
		(property "Dielectric" ""
			(at 0 0 270)
			(unlocked yes)
			(layer "F.Fab")
			(hide yes)
			(effects
				(font
					(size 1 1)
					(thickness 0.15)
				)
			)
		)
		(sheetname "/Supply/DC-DC AUX, MGT/")
		(sheetfile "dc-dc-aux-mgt.kicad_sch")
		(attr smd)
		(fp_line
			(start -0.15 0.4)
			(end 0.15 0.4)
			(stroke
				(width 0.15)
				(type solid)
			)
			(layer "F.SilkS")
		)
		(fp_line
			(start -0.15 -0.4)
			(end 0.15 -0.4)
			(stroke
				(width 0.15)
				(type solid)
			)
			(layer "F.SilkS")
		)
		(fp_rect
			(start -1.25 -0.65)
			(end 1.25 0.65)
			(stroke
				(width 0.05)
				(type solid)
			)
			(fill no)
			(layer "F.CrtYd")
		)
		(fp_rect
			(start -0.8 -0.4)
			(end 0.8 0.4)
			(stroke
				(width 0.15)
				(type solid)
			)
			(fill no)
			(layer "F.Fab")
		)
		(fp_text user "Author: Antmicro"
			(at -1.682 4.894 270)
			(layer "F.Fab")
			(effects
				(font
					(size 0.7 0.7)
					(thickness 0.15)
				)
				(justify left bottom)
			)
		)
		(fp_text user "License: Apache-2.0"
			(at -1.682 5.895 270)
			(layer "F.Fab")
			(effects
				(font
					(size 0.7 0.7)
					(thickness 0.15)
				)
				(justify left bottom)
			)
		)
		(fp_text user "${REFERENCE}"
			(at -1.682 3.895 270)
			(layer "F.Fab")
			(effects
				(font
					(size 0.7 0.7)
					(thickness 0.15)
				)
				(justify left bottom)
			)
		)
		(pad "1" smd roundrect
			(at -0.7 0 270)
			(size 0.8 1)
			(layers "F.Cu" "F.Mask" "F.Paste")
			(roundrect_rratio 0.2)
			(net 1 "GND")
			(pintype "passive")
		)
		(pad "2" smd roundrect
			(at 0.7 0 270)
			(size 0.8 1)
			(layers "F.Cu" "F.Mask" "F.Paste")
			(roundrect_rratio 0.2)
			(net 37 "/Supply/DC-DC AUX, MGT/1V8_local")
			(pintype "passive")
		)
	)
	(footprint "antmicro-footprints:R_0402_1005Metric"
		(layer "F.Cu")
		(at 116.256 177.3375)
		(descr "Resistor SMD 0402")
		(tags "resistor SMD 0402")
		(property "Reference" "R73"
			(at 0.9 0.45 0)
			(layer "F.SilkS")
			(effects
				(font
					(size 0.7 0.7)
					(thickness 0.15)
				)
				(justify left bottom)
			)
		)
		(property "Value" "R_2k2_0402"
			(at -1.011843 1.772047 0)
			(layer "F.Fab")
			(effects
				(font
					(size 0.7 0.7)
					(thickness 0.15)
				)
				(justify left bottom)
			)
		)
		(property "Datasheet" "https://www.bourns.com/docs/product-datasheets/cr.pdf"
			(at 0 0 0)
			(layer "F.Fab")
			(hide yes)
			(effects
				(font
					(size 1.27 1.27)
					(thickness 0.15)
				)
			)
		)
		(property "MPN" "CR0402-FX-2201GLF"
			(at 0 0 0)
			(unlocked yes)
			(layer "F.Fab")
			(hide yes)
			(effects
				(font
					(size 1 1)
					(thickness 0.15)
				)
			)
		)
		(property "Manufacturer" "Bourns"
			(at 0 0 0)
			(unlocked yes)
			(layer "F.Fab")
			(hide yes)
			(effects
				(font
					(size 1 1)
					(thickness 0.15)
				)
			)
		)
		(property "License" "Apache-2.0"
			(at 0 0 0)
			(unlocked yes)
			(layer "F.Fab")
			(hide yes)
			(effects
				(font
					(size 1 1)
					(thickness 0.15)
				)
			)
		)
		(property "Author" "Antmicro"
			(at 0 0 0)
			(unlocked yes)
			(layer "F.Fab")
			(hide yes)
			(effects
				(font
					(size 1 1)
					(thickness 0.15)
				)
			)
		)
		(property "Val" "2k2"
			(at 0 0 0)
			(unlocked yes)
			(layer "F.Fab")
			(hide yes)
			(effects
				(font
					(size 1 1)
					(thickness 0.15)
				)
			)
		)
		(property "Tolerance" "1%"
			(at 0 0 0)
			(unlocked yes)
			(layer "F.Fab")
			(hide yes)
			(effects
				(font
					(size 1 1)
					(thickness 0.15)
				)
			)
		)
		(property "Public" ""
			(at 0 0 0)
			(unlocked yes)
			(layer "F.Fab")
			(hide yes)
			(effects
				(font
					(size 1 1)
					(thickness 0.15)
				)
			)
		)
		(sheetname "/HDMI + SD Card/")
		(sheetfile "hdmi-sd-card.kicad_sch")
		(attr smd)
		(fp_rect
			(start -0.925 -0.47)
			(end 0.925 0.47)
			(stroke
				(width 0.05)
				(type default)
			)
			(fill no)
			(layer "F.CrtYd")
		)
		(fp_rect
			(start -0.5 -0.25)
			(end 0.5 0.25)
			(stroke
				(width 0.15)
				(type solid)
			)
			(fill no)
			(layer "F.Fab")
		)
		(fp_text user "License: Apache-2.0"
			(at -0.95 5.169 0)
			(layer "F.Fab")
			(effects
				(font
					(size 0.7 0.7)
					(thickness 0.15)
				)
				(justify left bottom)
			)
		)
		(fp_text user "Author: Antmicro"
			(at -0.95 4.169 0)
			(layer "F.Fab")
			(effects
				(font
					(size 0.7 0.7)
					(thickness 0.15)
				)
				(justify left bottom)
			)
		)
		(fp_text user "${REFERENCE}"
			(at -0.95 3.168 0)
			(layer "F.Fab")
			(effects
				(font
					(size 0.7 0.7)
					(thickness 0.15)
				)
				(justify left bottom)
			)
		)
		(pad "1" smd roundrect
			(at -0.48 0)
			(size 0.59 0.64)
			(layers "F.Cu" "F.Mask" "F.Paste")
			(roundrect_rratio 0.25)
			(net 467 "/HDMI + SD Card/HDMI_OUT_C.SCL")
			(pintype "passive")
		)
		(pad "2" smd roundrect
			(at 0.48 0)
			(size 0.59 0.64)
			(layers "F.Cu" "F.Mask" "F.Paste")
			(roundrect_rratio 0.25)
			(net 8 "/HDMI + SD Card/HDMI_CONN_5V")
			(pintype "passive")
		)
	)
	(footprint "antmicro-footprints:TP_SMD_1mm"
		(layer "F.Cu")
		(at 256.824499 134.649)
		(property "Reference" "TP19"
			(at 0 -0.731898 0)
			(layer "F.SilkS")
			(hide yes)
			(effects
				(font
					(size 0.7 0.7)
					(thickness 0.15)
				)
				(justify left bottom)
			)
		)
		(property "Value" "TP_1mm_SMD"
			(at 0 1.4 0)
			(layer "F.Fab")
			(effects
				(font
					(size 0.7 0.7)
					(thickness 0.15)
				)
				(justify left bottom)
			)
		)
		(property "MPN" ""
			(at 0 0 0)
			(unlocked yes)
			(layer "F.Fab")
			(hide yes)
			(effects
				(font
					(size 1 1)
					(thickness 0.15)
				)
			)
		)
		(property "Manufacturer" ""
			(at 0 0 0)
			(unlocked yes)
			(layer "F.Fab")
			(hide yes)
			(effects
				(font
					(size 1 1)
					(thickness 0.15)
				)
			)
		)
		(property "Author" "Antmicro"
			(at 0 0 0)
			(unlocked yes)
			(layer "F.Fab")
			(hide yes)
			(effects
				(font
					(size 1 1)
					(thickness 0.15)
				)
			)
		)
		(property "License" "Apache-2.0"
			(at 0 0 0)
			(unlocked yes)
			(layer "F.Fab")
			(hide yes)
			(effects
				(font
					(size 1 1)
					(thickness 0.15)
				)
			)
		)
		(sheetname "/Supply/")
		(sheetfile "supply.kicad_sch")
		(attr exclude_from_pos_files)
		(fp_circle
			(center 0 0)
			(end 0.6 0)
			(stroke
				(width 0.05)
				(type default)
			)
			(fill no)
			(layer "F.CrtYd")
		)
		(fp_text user "License: Apache-2.0"
			(at -0.5 5.2 0)
			(layer "F.Fab")
			(effects
				(font
					(size 0.7 0.7)
					(thickness 0.15)
				)
				(justify left bottom)
			)
		)
		(fp_text user "${REFERENCE}"
			(at -0.5 2.8 0)
			(layer "F.Fab")
			(effects
				(font
					(size 0.7 0.7)
					(thickness 0.15)
				)
				(justify left bottom)
			)
		)
		(fp_text user "Author: Antmicro"
			(at -0.5 4 0)
			(layer "F.Fab")
			(effects
				(font
					(size 0.7 0.7)
					(thickness 0.15)
				)
				(justify left bottom)
			)
		)
		(pad "1" smd circle
			(at 0 0)
			(size 1 1)
			(layers "F.Cu" "F.Mask")
			(net 38 "+3V3_AON")
			(pinfunction "1")
			(pintype "passive")
		)
	)
	(footprint "antmicro-footprints:USON-10_2.5x1mm_P0.5mm"
		(layer "F.Cu")
		(at 113.530499 182.5525 180)
		(descr "USON-10 2.5x1mm_ Pitch 0.5mm")
		(tags "USON-10 2.5x1mm Pitch 0.5mm")
		(property "Reference" "U10"
			(at -1.819501 0.7025 90)
			(layer "F.SilkS")
			(effects
				(font
					(size 0.7 0.7)
					(thickness 0.15)
				)
				(justify right bottom)
			)
		)
		(property "Value" "TPD4E05U06QDQARQ1"
			(at 0.018 2.499 0)
			(layer "F.Fab")
			(effects
				(font
					(size 0.7 0.7)
					(thickness 0.15)
				)
				(justify right bottom)
			)
		)
		(property "Datasheet" "https://www.ti.com/lit/ds/symlink/tpd4e05u06-q1.pdf?HQS=dis-mous-null-mousermode-dsf-pf-null-wwe&ts=1663591265741&ref_url=https%253A%252F%252Fwww.mouser.com%252F"
			(at 0 0 180)
			(layer "F.Fab")
			(hide yes)
			(effects
				(font
					(size 1.27 1.27)
					(thickness 0.15)
				)
			)
		)
		(property "Manufacturer" "Texas Instruments"
			(at 0 0 180)
			(unlocked yes)
			(layer "F.Fab")
			(hide yes)
			(effects
				(font
					(size 1 1)
					(thickness 0.15)
				)
			)
		)
		(property "MPN" "TPD4E05U06QDQARQ1"
			(at 0 0 180)
			(unlocked yes)
			(layer "F.Fab")
			(hide yes)
			(effects
				(font
					(size 1 1)
					(thickness 0.15)
				)
			)
		)
		(property "Author" "Antmicro"
			(at 0 0 180)
			(unlocked yes)
			(layer "F.Fab")
			(hide yes)
			(effects
				(font
					(size 1 1)
					(thickness 0.15)
				)
			)
		)
		(property "License" "Apache-2.0"
			(at 0 0 180)
			(unlocked yes)
			(layer "F.Fab")
			(hide yes)
			(effects
				(font
					(size 1 1)
					(thickness 0.15)
				)
			)
		)
		(sheetname "/HDMI + SD Card/")
		(sheetfile "hdmi-sd-card.kicad_sch")
		(attr smd)
		(fp_line
			(start 0.498 1.398)
			(end -0.5 1.398)
			(stroke
				(width 0.15)
				(type solid)
			)
			(layer "F.SilkS")
		)
		(fp_line
			(start 0.498 -1.401)
			(end -0.5 -1.401)
			(stroke
				(width 0.15)
				(type solid)
			)
			(layer "F.SilkS")
		)
		(fp_circle
			(center -0.68 -1.27)
			(end -0.63 -1.27)
			(stroke
				(width 0.15)
				(type solid)
			)
			(fill yes)
			(layer "F.SilkS")
		)
		(fp_rect
			(start -0.8 -1.5)
			(end 0.8 1.499)
			(stroke
				(width 0.05)
				(type solid)
			)
			(fill no)
			(layer "F.CrtYd")
		)
		(fp_line
			(start 0.498 -1.25)
			(end 0.498 1.249)
			(stroke
				(width 0.15)
				(type solid)
			)
			(layer "F.Fab")
		)
		(fp_line
			(start 0.498 -1.25)
			(end -0.25 -1.25)
			(stroke
				(width 0.15)
				(type solid)
			)
			(layer "F.Fab")
		)
		(fp_line
			(start -0.25 -1.25)
			(end -0.5 -1)
			(stroke
				(width 0.15)
				(type solid)
			)
			(layer "F.Fab")
		)
		(fp_line
			(start -0.5 1.249)
			(end 0.498 1.249)
			(stroke
				(width 0.15)
				(type solid)
			)
			(layer "F.Fab")
		)
		(fp_line
			(start -0.5 -1)
			(end -0.5 1.249)
			(stroke
				(width 0.15)
				(type solid)
			)
			(layer "F.Fab")
		)
		(fp_text user "License: Apache-2.0"
			(at -0.802 6.9 180)
			(layer "F.Fab")
			(effects
				(font
					(size 0.7 0.7)
					(thickness 0.15)
				)
				(justify left bottom)
			)
		)
		(fp_text user "${REFERENCE}"
			(at -0.802 4.498 180)
			(layer "F.Fab")
			(effects
				(font
					(size 0.7 0.7)
					(thickness 0.15)
				)
				(justify left bottom)
			)
		)
		(fp_text user "Author: Antmicro"
			(at -0.802 5.7 180)
			(layer "F.Fab")
			(effects
				(font
					(size 0.7 0.7)
					(thickness 0.15)
				)
				(justify left bottom)
			)
		)
		(pad "1" smd roundrect
			(at -0.387 -1 90)
			(size 0.25 0.55)
			(layers "F.Cu" "F.Mask" "F.Paste")
			(roundrect_rratio 0.25)
			(net 654 "/HDMI + SD Card/HDMI_OUT_CONN_D2_P")
			(pintype "passive")
		)
		(pad "2" smd roundrect
			(at -0.387 -0.5 90)
			(size 0.25 0.55)
			(layers "F.Cu" "F.Mask" "F.Paste")
			(roundrect_rratio 0.25)
			(net 655 "/HDMI + SD Card/HDMI_OUT_CONN_D2_N")
			(pintype "passive")
		)
		(pad "3" smd roundrect
			(at -0.387 0 90)
			(size 0.4 0.55)
			(layers "F.Cu" "F.Mask" "F.Paste")
			(roundrect_rratio 0.25)
			(net 1 "GND")
			(pintype "power_in")
		)
		(pad "4" smd roundrect
			(at -0.387 0.498 90)
			(size 0.25 0.55)
			(layers "F.Cu" "F.Mask" "F.Paste")
			(roundrect_rratio 0.25)
			(net 656 "/HDMI + SD Card/HDMI_OUT_CONN_D1_P")
			(pintype "passive")
		)
		(pad "5" smd roundrect
			(at -0.387 0.998 90)
			(size 0.25 0.55)
			(layers "F.Cu" "F.Mask" "F.Paste")
			(roundrect_rratio 0.25)
			(net 657 "/HDMI + SD Card/HDMI_OUT_CONN_D1_N")
			(pintype "passive")
		)
		(pad "6" smd roundrect
			(at 0.385 0.998 90)
			(size 0.25 0.55)
			(layers "F.Cu" "F.Mask" "F.Paste")
			(roundrect_rratio 0.25)
			(net 657 "/HDMI + SD Card/HDMI_OUT_CONN_D1_N")
			(pintype "passive")
		)
		(pad "7" smd roundrect
			(at 0.385 0.498 90)
			(size 0.25 0.55)
			(layers "F.Cu" "F.Mask" "F.Paste")
			(roundrect_rratio 0.25)
			(net 656 "/HDMI + SD Card/HDMI_OUT_CONN_D1_P")
			(pintype "passive")
		)
		(pad "8" smd roundrect
			(at 0.385 0 90)
			(size 0.4 0.55)
			(layers "F.Cu" "F.Mask" "F.Paste")
			(roundrect_rratio 0.25)
			(net 1 "GND")
			(pintype "passive")
		)
		(pad "9" smd roundrect
			(at 0.385 -0.5 90)
			(size 0.25 0.55)
			(layers "F.Cu" "F.Mask" "F.Paste")
			(roundrect_rratio 0.25)
			(net 655 "/HDMI + SD Card/HDMI_OUT_CONN_D2_N")
			(pintype "passive")
		)
		(pad "10" smd roundrect
			(at 0.385 -1 90)
			(size 0.25 0.55)
			(layers "F.Cu" "F.Mask" "F.Paste")
			(roundrect_rratio 0.25)
			(net 654 "/HDMI + SD Card/HDMI_OUT_CONN_D2_P")
			(pintype "passive")
		)
	)
)
